# T6G (Grand Teton) — schematic parts with pin connectivity, parts 1362–1538 of 8303; source: Cadence DE-HDL packaged netlist (pstxprt.dat, pstxnet.dat, pstchip.dat)

C2035  Q_CAP  1UF 25V 10% X6S  pkg C0402  page 234 : 1 = P3V3_AUX_USB_HUB ; 2 = GND
C2038  Q_CAP  10UF 6.3V 20% X6S  pkg C0402  page 234 : 1 = P3V3_AUX_USB_HUB ; 2 = GND
C2039  Q_CAP  0.1UF 25V 10% X7R  pkg 0402  page 234 : 1 = P3V3_AUX_USB_HUB ; 2 = GND
C2040  Q_CAP  0.1UF 25V 10% X7R  pkg 0402  page 234 : 1 = P3V3_AUX_USB_HUB ; 2 = GND
C2041  Q_CAP  1UF 25V 10% X6S  pkg C0402  page 234 : 1 = RST_USB_HUB_R_N ; 2 = GND
C2042  Q_CAP  100PF 50V 5% EMPTY  pkg 0402  page 257 : 1 = P3V3_AUX_ADC_MAM ; 2 = GND
C2043  Q_CAP  100PF 50V 5% EMPTY  pkg 0402  page 257 : 1 = P3V3_ADC_MAM ; 2 = GND
C2044  Q_CAP  100PF 50V 5% EMPTY  pkg 0402  page 257 : 1 = P5V_ADC_MAM ; 2 = GND
C2045  Q_CAP  100PF 50V 5% EMPTY  pkg 0402  page 257 : 1 = P3V3_PDB_AUX_ADC_MAM ; 2 = GND
C2046  Q_CAP  0.1UF 25V 10% X7R  pkg 0402  page 257 : 1 = P12V_AUX_ADC_TIC ; 2 = GND
C2047  Q_CAP  0.1UF 25V 10% X7R  pkg 0402  page 257 : 1 = P3V3_AUX_ADC_TIC ; 2 = GND
C2048  Q_CAP  0.1UF 25V 10% X7R  pkg 0402  page 257 : 1 = P3V3_ADC_TIC ; 2 = GND
C2049  Q_CAP  0.1UF 25V 10% X7R  pkg 0402  page 257 : 1 = P5V_ADC_TIC ; 2 = GND
C2050  Q_CAP  0.1UF 25V 10% X7R  pkg 0402  page 257 : 1 = P3V3_PDB_AUX_ADC_TIC ; 2 = GND
C2051  Q_CAP  0.1UF 25V 10% X7R  pkg 0402  page 257 : 1 = P3V3_ADC128_VCC ; 2 = GND
C2052  Q_CAP  0.1UF 25V 10% X7R  pkg 0402  page 257 : 1 = P3V3_ADC128_VCC ; 2 = GND
C2056  Q_CAP  0.1UF 25V 10% X7R  pkg 0402  page 252 : 1 = P3V3_AUX ; 2 = GND
C2067  Q_CAP  0.1UF 25V 10% X7R  pkg 0402  page 236 : 1 = P3V3_AUX ; 2 = GND
C2069  Q_CAP  0.1UF 25V 10% X7R  pkg 0402  page 236 : 1 = P3V3_E1S_0_R ; 2 = GND
C2071  Q_CAP  0.1UF 25V 10% X7R  pkg 0402  page 236 : 1 = VSENSE_P3V3_INA230_2_INP ; 2 = VSENSE_P3V3_INA230_2_INN
C2073  Q_CAP_DIFFBUS  DIFF BUS_0.22UF 6.3V 20% X6S  pkg C0201  page 53 : 1 = P3E_CPU1_P5_TX_C_DP<1> ; 2 = P3E_CPU1_P5_TX_DP<1>
C2074  Q_CAP_DIFFBUS  DIFF BUS_0.22UF 6.3V 20% X6S  pkg C0201  page 53 : 1 = P3E_CPU1_P5_TX_C_DN<1> ; 2 = P3E_CPU1_P5_TX_DN<1>
C2075  Q_CAP_DIFFBUS  DIFF BUS_0.22UF 6.3V 20% X6S  pkg C0201  page 53 : 1 = P3E_CPU1_P5_TX_C_DP<0> ; 2 = P3E_CPU1_P5_TX_DP<0>
C2076  Q_CAP_DIFFBUS  DIFF BUS_0.22UF 6.3V 20% X6S  pkg C0201  page 53 : 1 = P3E_CPU1_P5_TX_C_DN<0> ; 2 = P3E_CPU1_P5_TX_DN<0>
C2077  Q_CAP_DIFFBUS  DIFF BUS_0.22UF 6.3V 20% X6S  pkg C0201  page 26 : 1 = P2E_CPU0_P5_TX_DP ; 2 = P2E_CPU0_P5_TX_C_DP
C2078  Q_CAP_DIFFBUS  DIFF BUS_0.22UF 6.3V 20% X6S  pkg C0201  page 26 : 1 = P2E_CPU0_P5_TX_DN ; 2 = P2E_CPU0_P5_TX_C_DN
C2102  Q_CAP  22UF 4V 20% X6S  pkg C0402  page 74 : 1 = PVDDIO_P1 ; 2 = GND
C2103  Q_CAP  22UF 4V 20% X6S  pkg C0402  page 74 : 1 = PVDDIO_P1 ; 2 = GND
C2104  Q_CAP  22UF 4V 20% X6S  pkg C0402  page 74 : 1 = PVDDIO_P1 ; 2 = GND
C2105  Q_CAP  22UF 4V 20% X6S  pkg C0402  page 74 : 1 = PVDDIO_P1 ; 2 = GND
C2106  Q_CAP  22UF 4V 20% X6S  pkg C0402  page 74 : 1 = PVDDIO_P1 ; 2 = GND
C2107  Q_CAP  22UF 4V 20% X6S  pkg C0402  page 74 : 1 = PVDDIO_P1 ; 2 = GND
C2108  Q_CAP  22UF 4V 20% X6S  pkg C0402  page 74 : 1 = PVDDIO_P1 ; 2 = GND
C2109  Q_CAP  22UF 4V 20% X6S  pkg C0402  page 74 : 1 = PVDDIO_P1 ; 2 = GND
C2110  Q_CAP  22UF 4V 20% X6S  pkg C0402  page 74 : 1 = PVDDIO_P1 ; 2 = GND
C2111  Q_CAP  22UF 4V 20% X6S  pkg C0402  page 74 : 1 = PVDDIO_P1 ; 2 = GND
C2112  Q_CAP  22UF 4V 20% X6S  pkg C0402  page 74 : 1 = PVDDIO_P1 ; 2 = GND
C2113  Q_CAP  22UF 4V 20% X6S  pkg C0402  page 74 : 1 = PVDD11_S3_P1 ; 2 = GND
C2114  Q_CAP  22UF 4V 20% X6S  pkg C0402  page 74 : 1 = PVDD11_S3_P1 ; 2 = GND
C2115  Q_CAP  22UF 4V 20% X6S  pkg C0402  page 74 : 1 = PVDD11_S3_P1 ; 2 = GND
C2116  Q_CAP  22UF 4V 20% X6S  pkg C0402  page 74 : 1 = PVDDIO_P1 ; 2 = GND
C2117  Q_CAP  22UF 4V 20% X6S  pkg C0402  page 74 : 1 = PVDDIO_P1 ; 2 = GND
C2118  Q_CAP  22UF 4V 20% X6S  pkg C0402  page 74 : 1 = PVDD11_S3_P1 ; 2 = GND
C2119  Q_CAP  22UF 4V 20% X6S  pkg C0402  page 74 : 1 = PVDD11_S3_P1 ; 2 = GND
C2120  Q_CAP  22UF 4V 20% X6S  pkg C0402  page 74 : 1 = PVDD11_S3_P1 ; 2 = GND
C2121  Q_CAP  22UF 4V 20% X6S  pkg C0402  page 74 : 1 = PVDD11_S3_P1 ; 2 = GND
C2122  Q_CAP  22UF 4V 20% X6S  pkg C0402  page 74 : 1 = PVDDIO_P1 ; 2 = GND
C2123  Q_CAP  22UF 4V 20% X6S  pkg C0402  page 74 : 1 = PVDDIO_P1 ; 2 = GND
C2124  Q_CAP  22UF 4V 20% X6S  pkg C0402  page 74 : 1 = PVDD11_S3_P1 ; 2 = GND
C2125  Q_CAP  22UF 4V 20% X6S  pkg C0402  page 74 : 1 = PVDD11_S3_P1 ; 2 = GND
C2126  Q_CAP  22UF 4V 20% X6S  pkg C0402  page 74 : 1 = PVDD11_S3_P1 ; 2 = GND
C2127  Q_CAP  22UF 4V 20% X6S  pkg C0402  page 74 : 1 = PVDDIO_P1 ; 2 = GND
C2128  Q_CAP  22UF 4V 20% X6S  pkg C0402  page 74 : 1 = PVDD11_S3_P1 ; 2 = GND
C2129  Q_CAP  22UF 4V 20% X6S  pkg C0402  page 68 : 1 = PVDDCR_SOC_P0 ; 2 = GND
C2130  Q_CAP  22UF 4V 20% X6S  pkg C0402  page 68 : 1 = PVDDCR_SOC_P0 ; 2 = GND
C2131  Q_CAP  22UF 4V 20% X6S  pkg C0402  page 68 : 1 = PVDDIO_P0 ; 2 = GND
C2132  Q_CAP  22UF 4V 20% X6S  pkg C0402  page 68 : 1 = PVDD11_S3_P0 ; 2 = GND
C2133  Q_CAP  22UF 4V 20% X6S  pkg C0402  page 68 : 1 = PVDD11_S3_P0 ; 2 = GND
C2134  Q_CAP  22UF 4V 20% X6S  pkg C0402  page 68 : 1 = PVDDCR_SOC_P0 ; 2 = GND
C2135  Q_CAP  22UF 4V 20% X6S  pkg C0402  page 68 : 1 = PVDDCR_SOC_P0 ; 2 = GND
C2136  Q_CAP  22UF 4V 20% X6S  pkg C0402  page 68 : 1 = PVDDIO_P0 ; 2 = GND
C2137  Q_CAP  22UF 4V 20% X6S  pkg C0402  page 68 : 1 = PVDD11_S3_P0 ; 2 = GND
C2138  Q_CAP  22UF 4V 20% X6S  pkg C0402  page 68 : 1 = PVDD11_S3_P0 ; 2 = GND
C2139  Q_CAP  22UF 4V 20% X6S  pkg C0402  page 68 : 1 = PVDDCR_SOC_P0 ; 2 = GND
C2140  Q_CAP  22UF 4V 20% X6S  pkg C0402  page 68 : 1 = PVDDCR_SOC_P0 ; 2 = GND
C2141  Q_CAP  22UF 4V 20% X6S  pkg C0402  page 68 : 1 = PVDDIO_P0 ; 2 = GND
C2142  Q_CAP  22UF 4V 20% X6S  pkg C0402  page 68 : 1 = PVDD11_S3_P0 ; 2 = GND
C2143  Q_CAP  22UF 4V 20% X6S  pkg C0402  page 68 : 1 = PVDDCR_SOC_P0 ; 2 = GND
C2144  Q_CAP  22UF 4V 20% X6S  pkg C0402  page 68 : 1 = PVDDCR_SOC_P0 ; 2 = GND
C2145  Q_CAP  22UF 4V 20% X6S  pkg C0402  page 68 : 1 = PVDDIO_P0 ; 2 = GND
C2146  Q_CAP  22UF 4V 20% X6S  pkg C0402  page 68 : 1 = PVDD11_S3_P0 ; 2 = GND
C2147  Q_CAP  22UF 4V 20% X6S  pkg C0402  page 68 : 1 = PVDDCR_SOC_P0 ; 2 = GND
C2148  Q_CAP  22UF 4V 20% X6S  pkg C0402  page 68 : 1 = PVDDCR_SOC_P0 ; 2 = GND
C2149  Q_CAP  22UF 4V 20% X6S  pkg C0402  page 68 : 1 = PVDDIO_P0 ; 2 = GND
C2150  Q_CAP  22UF 4V 20% X6S  pkg C0402  page 68 : 1 = PVDD11_S3_P0 ; 2 = GND
C2151  Q_CAP  22UF 4V 20% X6S  pkg C0402  page 68 : 1 = PVDDCR_SOC_P0 ; 2 = GND
C2152  Q_CAP  22UF 4V 20% X6S  pkg C0402  page 68 : 1 = PVDDCR_SOC_P0 ; 2 = GND
C2153  Q_CAP  22UF 4V 20% X6S  pkg C0402  page 68 : 1 = PVDD11_S3_P0 ; 2 = GND
C2154  Q_CAP  22UF 4V 20% X6S  pkg C0402  page 68 : 1 = PVDDCR_SOC_P0 ; 2 = GND
C2155  Q_CAP  22UF 4V 20% X6S  pkg C0402  page 68 : 1 = PVDDCR_SOC_P0 ; 2 = GND
C2156  Q_CAP  22UF 4V 20% X6S  pkg C0402  page 68 : 1 = PVDD11_S3_P0 ; 2 = GND
C2157  Q_CAP  22UF 4V 20% X6S  pkg C0402  page 68 : 1 = PVDDCR_SOC_P0 ; 2 = GND
C2158  Q_CAP  22UF 4V 20% X6S  pkg C0402  page 68 : 1 = PVDD11_S3_P0 ; 2 = GND
C2159  Q_CAP  22UF 4V 20% X6S  pkg C0402  page 68 : 1 = PVDDCR_SOC_P0 ; 2 = GND
C2160  Q_CAP  22UF 4V 20% X6S  pkg C0402  page 68 : 1 = PVDD11_S3_P0 ; 2 = GND
C2161  Q_CAP  22UF 4V 20% X6S  pkg C0402  page 68 : 1 = PVDDCR_SOC_P0 ; 2 = GND
C2162  Q_CAP  22UF 4V 20% X6S  pkg C0402  page 68 : 1 = PVDD11_S3_P0 ; 2 = GND
C2163  Q_CAP  22UF 4V 20% X6S  pkg C0402  page 68 : 1 = PVDD18_S5_P0 ; 2 = GND
C2164  Q_CAP  22UF 4V 20% X6S  pkg C0402  page 68 : 1 = PVDD18_S5_P0 ; 2 = GND
C2165  Q_CAP  22UF 4V 20% X6S  pkg C0402  page 69 : 1 = PVDDCR_CPU0_P0 ; 2 = GND
C2166  Q_CAP  22UF 4V 20% X6S  pkg C0402  page 69 : 1 = PVDDCR_CPU0_P0 ; 2 = GND
C2167  Q_CAP  22UF 4V 20% X6S  pkg C0402  page 69 : 1 = PVDDCR_CPU0_P0 ; 2 = GND
C2169  Q_CAP  22UF 4V 20% X6S  pkg C0402  page 69 : 1 = PVDDCR_CPU0_P0 ; 2 = GND
C2170  Q_CAP  22UF 4V 20% X6S  pkg C0402  page 69 : 1 = PVDDCR_CPU0_P0 ; 2 = GND
C2171  Q_CAP  22UF 4V 20% X6S  pkg C0402  page 69 : 1 = PVDDCR_CPU0_P0 ; 2 = GND
C2173  Q_CAP  22UF 4V 20% X6S  pkg C0402  page 69 : 1 = PVDDCR_CPU0_P0 ; 2 = GND
C2174  Q_CAP  22UF 4V 20% X6S  pkg C0402  page 69 : 1 = PVDDCR_CPU0_P0 ; 2 = GND
C2175  Q_CAP  22UF 4V 20% X6S  pkg C0402  page 69 : 1 = PVDDCR_CPU0_P0 ; 2 = GND
C2176  Q_CAP  100PF 50V 5% EMPTY  pkg 0402  page 257 : 1 = P12V_OCP_SFF_ISENSE_MAM ; 2 = GND
C2177  Q_CAP  22UF 4V 20% X6S  pkg C0402  page 69 : 1 = PVDDCR_CPU0_P0 ; 2 = GND
C2178  Q_CAP  22UF 4V 20% X6S  pkg C0402  page 69 : 1 = PVDDCR_CPU0_P0 ; 2 = GND
C2179  Q_CAP  100NF 50V 10% X7R  pkg C0402  page 268 : 1 = HSC_EN ; 2 = GND
C2181  Q_CAP  22UF 4V 20% X6S  pkg C0402  page 69 : 1 = PVDDCR_CPU0_P0 ; 2 = GND
C2182  Q_CAP  22UF 4V 20% X6S  pkg C0402  page 69 : 1 = PVDDCR_CPU0_P0 ; 2 = GND
C2183  Q_CAP  22UF 4V 20% X6S  pkg C0402  page 69 : 1 = PVDDCR_CPU0_P0 ; 2 = GND
C2185  Q_CAP  22UF 4V 20% X6S  pkg C0402  page 69 : 1 = PVDDCR_CPU0_P0 ; 2 = GND
C2186  Q_CAP  22UF 4V 20% X6S  pkg C0402  page 69 : 1 = PVDDCR_CPU0_P0 ; 2 = GND
C2189  Q_CAP  22UF 4V 20% X6S  pkg C0402  page 69 : 1 = PVDDCR_CPU0_P0 ; 2 = GND
C2190  Q_CAP  22UF 4V 20% X6S  pkg C0402  page 69 : 1 = PVDDCR_CPU0_P0 ; 2 = GND
C2192  Q_CAP  22UF 4V 20% X6S  pkg C0402  page 69 : 1 = PVDDCR_CPU0_P0 ; 2 = GND
C2193  Q_CAP  22UF 4V 20% X6S  pkg C0402  page 69 : 1 = PVDDCR_CPU0_P0 ; 2 = GND
C2194  Q_CAP  0.1UF 25V 10% X7R  pkg 0402  page 257 : 1 = P12V_E1S_0_ISENSE_TIC ; 2 = GND
C2195  Q_CAP  22UF 4V 20% X6S  pkg C0402  page 69 : 1 = PVDDCR_CPU0_P0 ; 2 = GND
C2196  Q_CAP  22UF 4V 20% X6S  pkg C0402  page 69 : 1 = PVDDCR_CPU0_P0 ; 2 = GND
C2198  Q_CAP  22UF 4V 20% X6S  pkg C0402  page 69 : 1 = PVDDCR_CPU0_P0 ; 2 = GND
C2199  Q_CAP  22UF 4V 20% X6S  pkg C0402  page 69 : 1 = PVDDCR_CPU0_P0 ; 2 = GND
C2201  Q_CAP  22UF 4V 20% X6S  pkg C0402  page 69 : 1 = PVDDCR_CPU1_P0 ; 2 = GND
C2202  Q_CAP  22UF 4V 20% X6S  pkg C0402  page 69 : 1 = PVDDCR_CPU1_P0 ; 2 = GND
C2203  Q_CAP  22UF 4V 20% X6S  pkg C0402  page 69 : 1 = PVDDCR_CPU1_P0 ; 2 = GND
C2204  Q_CAP  22UF 4V 20% X6S  pkg C0402  page 69 : 1 = PVDDCR_CPU1_P0 ; 2 = GND
C2205  Q_CAP  22UF 4V 20% X6S  pkg C0402  page 69 : 1 = PVDDCR_CPU1_P0 ; 2 = GND
C2207  Q_CAP  22UF 4V 20% X6S  pkg C0402  page 69 : 1 = PVDDCR_CPU1_P0 ; 2 = GND
C2208  Q_CAP  22UF 4V 20% X6S  pkg C0402  page 69 : 1 = PVDDCR_CPU1_P0 ; 2 = GND
C2209  Q_CAP  22UF 4V 20% X6S  pkg C0402  page 69 : 1 = PVDDCR_CPU1_P0 ; 2 = GND
C2210  Q_CAP  22UF 4V 20% X6S  pkg C0402  page 69 : 1 = PVDDCR_CPU1_P0 ; 2 = GND
C2211  Q_CAP  22UF 4V 20% X6S  pkg C0402  page 69 : 1 = PVDDCR_CPU1_P0 ; 2 = GND
C2213  Q_CAP  22UF 4V 20% X6S  pkg C0402  page 69 : 1 = PVDDCR_CPU1_P0 ; 2 = GND
C2214  Q_CAP  22UF 4V 20% X6S  pkg C0402  page 69 : 1 = PVDDCR_CPU1_P0 ; 2 = GND
C2215  Q_CAP  22UF 4V 20% X6S  pkg C0402  page 69 : 1 = PVDDCR_CPU1_P0 ; 2 = GND
C2216  Q_CAP  22UF 4V 20% X6S  pkg C0402  page 69 : 1 = PVDDCR_CPU1_P0 ; 2 = GND
C2217  Q_CAP  22UF 4V 20% X6S  pkg C0402  page 69 : 1 = PVDDCR_CPU1_P0 ; 2 = GND
C2219  Q_CAP  22UF 4V 20% X6S  pkg C0402  page 69 : 1 = PVDDCR_CPU1_P0 ; 2 = GND
C2220  Q_CAP  22UF 4V 20% X6S  pkg C0402  page 69 : 1 = PVDDCR_CPU1_P0 ; 2 = GND
C2221  Q_CAP  22UF 4V 20% X6S  pkg C0402  page 69 : 1 = PVDDCR_CPU1_P0 ; 2 = GND
C2222  Q_CAP  22UF 4V 20% X6S  pkg C0402  page 69 : 1 = PVDDCR_CPU1_P0 ; 2 = GND
C2223  Q_CAP  22UF 4V 20% X6S  pkg C0402  page 69 : 1 = PVDDCR_CPU1_P0 ; 2 = GND
C2225  Q_CAP  22UF 4V 20% X6S  pkg C0402  page 69 : 1 = PVDDCR_CPU1_P0 ; 2 = GND
C2226  Q_CAP  22UF 4V 20% X6S  pkg C0402  page 69 : 1 = PVDDCR_CPU1_P0 ; 2 = GND
C2227  Q_CAP  22UF 4V 20% X6S  pkg C0402  page 69 : 1 = PVDDCR_CPU1_P0 ; 2 = GND
C2228  Q_CAP  22UF 4V 20% X6S  pkg C0402  page 69 : 1 = PVDDCR_CPU1_P0 ; 2 = GND
C2229  Q_CAP  22UF 4V 20% X6S  pkg C0402  page 69 : 1 = PVDDCR_CPU1_P0 ; 2 = GND
C2231  Q_CAP  22UF 4V 20% X6S  pkg C0402  page 69 : 1 = PVDDCR_CPU1_P0 ; 2 = GND
C2232  Q_CAP  22UF 4V 20% X6S  pkg C0402  page 69 : 1 = PVDDCR_CPU1_P0 ; 2 = GND
C2233  Q_CAP  22UF 4V 20% X6S  pkg C0402  page 69 : 1 = PVDDCR_CPU1_P0 ; 2 = GND
C2234  Q_CAP  22UF 4V 20% X6S  pkg C0402  page 69 : 1 = PVDDCR_CPU1_P0 ; 2 = GND
C2237  Q_CAP  22UF 4V 20% X6S  pkg C0402  page 69 : 1 = PVDDCR_CPU1_P0 ; 2 = GND
C2238  Q_CAP  22UF 4V 20% X6S  pkg C0402  page 69 : 1 = PVDDCR_CPU1_P0 ; 2 = GND
C2239  Q_CAP  22UF 4V 20% X6S  pkg C0402  page 69 : 1 = PVDDCR_CPU1_P0 ; 2 = GND
C2240  Q_CAP  22UF 4V 20% X6S  pkg C0402  page 69 : 1 = PVDDCR_CPU1_P0 ; 2 = GND
C2243  Q_CAP  22UF 4V 20% X6S  pkg C0402  page 69 : 1 = PVDDCR_CPU1_P0 ; 2 = GND
C2244  Q_CAP  22UF 4V 20% X6S  pkg C0402  page 69 : 1 = PVDDCR_CPU1_P0 ; 2 = GND
C2245  Q_CAP  22UF 4V 20% X6S  pkg C0402  page 69 : 1 = PVDDCR_CPU1_P0 ; 2 = GND
C2246  Q_CAP  22UF 4V 20% X6S  pkg C0402  page 69 : 1 = PVDDCR_CPU1_P0 ; 2 = GND
C2248  Q_CAP  22UF 4V 20% X6S  pkg C0402  page 69 : 1 = PVDDCR_CPU1_P0 ; 2 = GND
C2249  Q_CAP  22UF 4V 20% X6S  pkg C0402  page 69 : 1 = PVDDCR_CPU1_P0 ; 2 = GND
C2250  Q_CAP  22UF 4V 20% X6S  pkg C0402  page 69 : 1 = PVDDCR_CPU1_P0 ; 2 = GND
C2251  Q_CAP  22UF 4V 20% X6S  pkg C0402  page 69 : 1 = PVDDCR_CPU1_P0 ; 2 = GND
C2253  Q_CAP  22UF 4V 20% X6S  pkg C0402  page 69 : 1 = PVDDCR_CPU1_P0 ; 2 = GND
C2254  Q_CAP  22UF 4V 20% X6S  pkg C0402  page 69 : 1 = PVDDCR_CPU1_P0 ; 2 = GND
C2255  Q_CAP  22UF 4V 20% X6S  pkg C0402  page 69 : 1 = PVDDCR_CPU1_P0 ; 2 = GND
C2256  Q_CAP  22UF 4V 20% X6S  pkg C0402  page 69 : 1 = PVDDCR_CPU1_P0 ; 2 = GND
C2257  Q_CAP  0.1UF 25V 10% X7R  pkg 0402  page 233 : 1 = VFG3P3_CLK_GEN ; 2 = GND
C2258  Q_CAP  22UF 4V 20% X6S  pkg C0402  page 72 : 1 = PVDDCR_SOC_P1 ; 2 = GND
C2259  Q_CAP  22UF 4V 20% X6S  pkg C0402  page 72 : 1 = PVDDCR_SOC_P1 ; 2 = GND
C2260  Q_CAP  22UF 4V 20% X6S  pkg C0402  page 72 : 1 = PVDDIO_P1 ; 2 = GND
C2261  Q_CAP  22UF 4V 20% X6S  pkg C0402  page 72 : 1 = PVDD11_S3_P1 ; 2 = GND
C2262  Q_CAP  22UF 4V 20% X6S  pkg C0402  page 72 : 1 = PVDD11_S3_P1 ; 2 = GND
C2263  Q_CAP  22UF 4V 20% X6S  pkg C0402  page 72 : 1 = PVDDCR_SOC_P1 ; 2 = GND
C2264  Q_CAP  22UF 4V 20% X6S  pkg C0402  page 72 : 1 = PVDDCR_SOC_P1 ; 2 = GND
C2265  Q_CAP  22UF 4V 20% X6S  pkg C0402  page 72 : 1 = PVDDIO_P1 ; 2 = GND
C2266  Q_CAP  22UF 4V 20% X6S  pkg C0402  page 72 : 1 = PVDD11_S3_P1 ; 2 = GND
C2267  Q_CAP  22UF 4V 20% X6S  pkg C0402  page 72 : 1 = PVDD11_S3_P1 ; 2 = GND
C2268  Q_CAP  22UF 4V 20% X6S  pkg C0402  page 72 : 1 = PVDDCR_SOC_P1 ; 2 = GND
C2269  Q_CAP  22UF 4V 20% X6S  pkg C0402  page 72 : 1 = PVDDCR_SOC_P1 ; 2 = GND
C2270  Q_CAP  22UF 4V 20% X6S  pkg C0402  page 72 : 1 = PVDDIO_P1 ; 2 = GND
C2271  Q_CAP  22UF 4V 20% X6S  pkg C0402  page 72 : 1 = PVDD11_S3_P1 ; 2 = GND
C2272  Q_CAP  22UF 4V 20% X6S  pkg C0402  page 72 : 1 = PVDDCR_SOC_P1 ; 2 = GND
